(kicad_pcb
	(version 20260206)
	(generator "pcbnew")
	(generator_version "10.0")
	(general
		(thickness 1.6)
		(legacy_teardrops no)
	)
	(paper "A4")
	(title_block
		(title "03242023_DA0F0TMBIJ0_F0T_Motherboard_J_brd_V01_OCP.brd")
		(comment 1 "Grand Teton / footprint 1682 of 6105 (U1), pads 2363-2476 of 4677")
	)
	(layers
		(0 "F.Cu" signal "TOP")
		(4 "In1.Cu" signal "GND")
		(6 "In2.Cu" signal "IN1")
		(8 "In3.Cu" signal "GND1")
		(10 "In4.Cu" signal "IN2")
		(12 "In5.Cu" signal "GND2")
		(14 "In6.Cu" signal "IN3")
		(16 "In7.Cu" signal "GND3")
		(18 "In8.Cu" signal "VCC")
		(20 "In9.Cu" signal "VCC1")
		(22 "In10.Cu" signal "GND4")
		(24 "In11.Cu" signal "IN4")
		(26 "In12.Cu" signal "GND5")
		(28 "In13.Cu" signal "IN5")
		(30 "In14.Cu" signal "GND6")
		(32 "In15.Cu" signal "IN6")
		(34 "In16.Cu" signal "GND7")
		(2 "B.Cu" signal "BOTTOM")
		(9 "F.Adhes" user "F.Adhesive")
		(11 "B.Adhes" user "B.Adhesive")
		(13 "F.Paste" user "Package Geometry/Pastemask Top")
		(15 "B.Paste" user "Package Geometry/Pastemask Bottom")
		(5 "F.SilkS" user "Ref Des/Silkscreen Top")
		(7 "B.SilkS" user "Ref Des/Silkscreen Bottom")
		(1 "F.Mask" user "Board Geometry/Soldermask Top")
		(3 "B.Mask" user "Board Geometry/Soldermask Bottom")
		(17 "Dwgs.User" user "User.Drawings")
		(19 "Cmts.User" user "User.Comments")
		(21 "Eco1.User" user "User.Eco1")
		(23 "Eco2.User" user "User.Eco2")
		(25 "Edge.Cuts" user "Board Geometry/Outline")
		(27 "Margin" user)
		(31 "F.CrtYd" user "Package Geometry/Place Bound Top")
		(29 "B.CrtYd" user "Package Geometry/Place Bound Bottom")
		(35 "F.Fab" user "Ref Des/Assembly Top")
		(33 "B.Fab" user "Ref Des/Assembly Bottom")
	)
	(footprint ""
		(layer "F.Cu")
		(at 111.93018 -251.76988 90)
		(property "Reference" "U1"
			(at -74.913236 41.548812 0)
			(unlocked yes)
			(layer "F.SilkS")
			(effects
				(font
					(size 1.6002 1.1938)
					(thickness 0.1524)
				)
				(justify left)
			)
		)
		(property "Value" ""
			(at 0 0 90)
			(layer "F.Fab")
			(effects
				(font
					(size 1.27 1.27)
				)
			)
		)
		(duplicate_pad_numbers_are_jumpers no)
		(pad "D32" smd circle
			(at -12.19454 -25.664414 270)
			(size 0.4318 0.4318)
			(layers "F.Cu" "F.Mask" "F.Paste")
			(net "GND")
		)
		(pad "D34" smd circle
			(at -10.566654 -25.664414 270)
			(size 0.4318 0.4318)
			(layers "F.Cu" "F.Mask" "F.Paste")
			(net "GND")
		)
		(pad "D36" smd circle
			(at -8.939022 -25.664414 270)
			(size 0.4318 0.4318)
			(layers "F.Cu" "F.Mask" "F.Paste")
			(net "GND")
		)
		(pad "D38" smd circle
			(at -7.311136 -25.664414 270)
			(size 0.4318 0.4318)
			(layers "F.Cu" "F.Mask" "F.Paste")
			(net "GND")
		)
		(pad "D40" smd circle
			(at -5.68325 -25.664414 270)
			(size 0.4318 0.4318)
			(layers "F.Cu" "F.Mask" "F.Paste")
			(net "GND")
		)
		(pad "D42" smd circle
			(at -4.055618 -25.664414 270)
			(size 0.4318 0.4318)
			(layers "F.Cu" "F.Mask" "F.Paste")
			(net "GND")
		)
		(pad "D44" smd circle
			(at -2.427732 -25.664414 270)
			(size 0.4318 0.4318)
			(layers "F.Cu" "F.Mask" "F.Paste")
			(net "GND")
		)
		(pad "D47" smd oval
			(at 1.613916 -25.554686 135)
			(size 0.381 0.4826)
			(drill
				(offset 0 -0.0508)
			)
			(layers "F.Cu" "F.Mask" "F.Paste")
			(net "GND")
		)
		(pad "D49" smd circle
			(at 3.241802 -25.554686 270)
			(size 0.4318 0.4318)
			(layers "F.Cu" "F.Mask" "F.Paste")
			(net "GND")
		)
		(pad "D51" smd circle
			(at 4.869434 -25.554686 270)
			(size 0.4318 0.4318)
			(layers "F.Cu" "F.Mask" "F.Paste")
			(net "GND")
		)
		(pad "D53" smd circle
			(at 6.49732 -25.554686 270)
			(size 0.4318 0.4318)
			(layers "F.Cu" "F.Mask" "F.Paste")
			(net "GND")
		)
		(pad "D55" smd circle
			(at 8.124952 -25.554686 270)
			(size 0.4318 0.4318)
			(layers "F.Cu" "F.Mask" "F.Paste")
			(net "GND")
		)
		(pad "D57" smd circle
			(at 9.752838 -25.554686 270)
			(size 0.4318 0.4318)
			(layers "F.Cu" "F.Mask" "F.Paste")
			(net "GND")
		)
		(pad "D59" smd circle
			(at 11.380724 -25.554686 270)
			(size 0.4318 0.4318)
			(layers "F.Cu" "F.Mask" "F.Paste")
			(net "GND")
		)
		(pad "D61" smd circle
			(at 13.008356 -25.554686 270)
			(size 0.4318 0.4318)
			(layers "F.Cu" "F.Mask" "F.Paste")
			(net "GND")
		)
		(pad "D63" smd circle
			(at 14.635988 -25.554686 270)
			(size 0.4318 0.4318)
			(layers "F.Cu" "F.Mask" "F.Paste")
			(net "GND")
		)
		(pad "D65" smd circle
			(at 16.263874 -25.554686 270)
			(size 0.4318 0.4318)
			(layers "F.Cu" "F.Mask" "F.Paste")
			(net "GND")
		)
		(pad "D67" smd circle
			(at 17.89176 -25.554686 270)
			(size 0.4318 0.4318)
			(layers "F.Cu" "F.Mask" "F.Paste")
			(net "GND")
		)
		(pad "D69" smd circle
			(at 19.519392 -25.554686 270)
			(size 0.4318 0.4318)
			(layers "F.Cu" "F.Mask" "F.Paste")
			(net "GND")
		)
		(pad "D71" smd circle
			(at 21.147278 -25.554686 270)
			(size 0.4318 0.4318)
			(layers "F.Cu" "F.Mask" "F.Paste")
			(net "GND")
		)
		(pad "D73" smd circle
			(at 22.77491 -25.554686 270)
			(size 0.4318 0.4318)
			(layers "F.Cu" "F.Mask" "F.Paste")
			(net "M_A_CPU1_SA_DQ<18>")
		)
		(pad "D75" smd circle
			(at 24.402796 -25.554686 270)
			(size 0.4318 0.4318)
			(layers "F.Cu" "F.Mask" "F.Paste")
			(net "M_A_CPU1_SA_DQ<5>")
		)
		(pad "D77" smd circle
			(at 26.030682 -25.554686 270)
			(size 0.4318 0.4318)
			(layers "F.Cu" "F.Mask" "F.Paste")
			(net "M_A_CPU1_SA_DQS_DP<0>")
		)
		(pad "D79" smd circle
			(at 27.658314 -25.554686 270)
			(size 0.4318 0.4318)
			(layers "F.Cu" "F.Mask" "F.Paste")
			(net "GND")
		)
		(pad "D81" smd circle
			(at 29.2862 -25.554686 270)
			(size 0.4318 0.4318)
			(layers "F.Cu" "F.Mask" "F.Paste")
			(net "GND")
		)
		(pad "D83" smd circle
			(at 30.914086 -25.554686 270)
			(size 0.4318 0.4318)
			(layers "F.Cu" "F.Mask" "F.Paste")
			(net "GND")
		)
		(pad "D85" smd oval
			(at 32.541718 -25.554686 45)
			(size 0.381 0.4826)
			(drill
				(offset 0 -0.0508)
			)
			(layers "F.Cu" "F.Mask" "F.Paste")
			(net "UPI_CPU1_CPU0_P2P2_DP<0>")
		)
		(pad "D87" smd oval
			(at 34.169604 -25.554686 45)
			(size 0.381 0.4826)
			(drill
				(offset 0 -0.0508)
			)
			(layers "F.Cu" "F.Mask" "F.Paste")
			(net "UPI_CPU1_CPU0_P2P2_DN<2>")
		)
		(pad "DA1" smd oval
			(at -37.425122 10.517886 180)
			(size 0.381 0.4826)
			(drill
				(offset 0 -0.0508)
			)
			(layers "F.Cu" "F.Mask" "F.Paste")
			(net "UPI_CPU0_CPU1_P0P1_DP<13>")
		)
		(pad "DA3" smd circle
			(at -35.797236 10.517886 270)
			(size 0.4318 0.4318)
			(layers "F.Cu" "F.Mask" "F.Paste")
			(net "PVCCINFAON_CPU1")
		)
		(pad "DA5" smd circle
			(at -34.169604 10.517886 270)
			(size 0.4318 0.4318)
			(layers "F.Cu" "F.Mask" "F.Paste")
			(net "UPI_CPU1_CPU0_P1P0_DN<12>")
		)
		(pad "DA7" smd circle
			(at -32.541718 10.517886 270)
			(size 0.4318 0.4318)
			(layers "F.Cu" "F.Mask" "F.Paste")
			(net "PVCCINFAON_CPU1")
		)
		(pad "DA9" smd circle
			(at -30.914086 10.517886 270)
			(size 0.4318 0.4318)
			(layers "F.Cu" "F.Mask" "F.Paste")
			(net "P5E_CPU1_PE2_RX_DN<2>")
		)
		(pad "DA11" smd circle
			(at -29.2862 10.517886 270)
			(size 0.4318 0.4318)
			(layers "F.Cu" "F.Mask" "F.Paste")
			(net "PVCCINFAON_CPU1")
		)
		(pad "DA13" smd circle
			(at -27.658314 10.517886 270)
			(size 0.4318 0.4318)
			(layers "F.Cu" "F.Mask" "F.Paste")
			(net "P5E_CPU1_PE2_TX_DN<2>")
		)
		(pad "DA15" smd circle
			(at -26.030682 10.517886 270)
			(size 0.4318 0.4318)
			(layers "F.Cu" "F.Mask" "F.Paste")
			(net "PVCCINFAON_CPU1")
		)
		(pad "DA17" smd circle
			(at -24.402796 10.517886 270)
			(size 0.4318 0.4318)
			(layers "F.Cu" "F.Mask" "F.Paste")
			(net "M_H_CPU1_SB_DQ<29>")
		)
		(pad "DA19" smd circle
			(at -22.77491 10.517886 270)
			(size 0.4318 0.4318)
			(layers "F.Cu" "F.Mask" "F.Paste")
			(net "GND")
		)
		(pad "DA21" smd circle
			(at -21.147278 10.517886 270)
			(size 0.4318 0.4318)
			(layers "F.Cu" "F.Mask" "F.Paste")
			(net "PVCCINFAON_CPU1")
		)
		(pad "DA23" smd circle
			(at -19.519392 10.517886 270)
			(size 0.4318 0.4318)
			(layers "F.Cu" "F.Mask" "F.Paste")
			(net "GND")
		)
		(pad "DA25" smd circle
			(at -17.89176 10.517886 270)
			(size 0.4318 0.4318)
			(layers "F.Cu" "F.Mask" "F.Paste")
			(net "GND")
		)
		(pad "DA27" smd circle
			(at -16.263874 10.517886 270)
			(size 0.4318 0.4318)
			(layers "F.Cu" "F.Mask" "F.Paste")
			(net "CLK_100M_DB2000_CPU1_BCLK3_DP")
		)
		(pad "DA29" smd circle
			(at -14.635988 10.517886 270)
			(size 0.4318 0.4318)
			(layers "F.Cu" "F.Mask" "F.Paste")
			(net "GND")
		)
		(pad "DA31" smd circle
			(at -13.008356 10.517886 270)
			(size 0.4318 0.4318)
			(layers "F.Cu" "F.Mask" "F.Paste")
			(net "GND")
		)
		(pad "DA33" smd circle
			(at -11.380724 10.517886 270)
			(size 0.4318 0.4318)
			(layers "F.Cu" "F.Mask" "F.Paste")
			(net "GND")
		)
		(pad "DA35" smd circle
			(at -9.752838 10.517886 270)
			(size 0.4318 0.4318)
			(layers "F.Cu" "F.Mask" "F.Paste")
			(net "GND")
		)
		(pad "DA37" smd circle
			(at -8.124952 10.517886 270)
			(size 0.4318 0.4318)
			(layers "F.Cu" "F.Mask" "F.Paste")
			(net "GND")
		)
		(pad "DA39" smd circle
			(at -6.49732 10.517886 270)
			(size 0.4318 0.4318)
			(layers "F.Cu" "F.Mask" "F.Paste")
			(net "TP_H_CPU1_PMSYNC_PCH_INTRP_R")
		)
		(pad "DA41" smd circle
			(at -4.869434 10.517886 270)
			(size 0.4318 0.4318)
			(layers "F.Cu" "F.Mask" "F.Paste")
			(net "GND")
		)
		(pad "DA43" smd circle
			(at -3.241802 10.517886 270)
			(size 0.4318 0.4318)
			(layers "F.Cu" "F.Mask" "F.Paste")
			(net "GND")
		)
		(pad "DA45" smd circle
			(at -1.613916 10.517886 270)
			(size 0.4318 0.4318)
			(layers "F.Cu" "F.Mask" "F.Paste")
			(net "NC_CPU1_DDR67_VIEWDIG0")
		)
		(pad "DA48" smd circle
			(at 2.427732 10.627868 270)
			(size 0.4318 0.4318)
			(layers "F.Cu" "F.Mask" "F.Paste")
			(net "GND")
		)
		(pad "DA50" smd circle
			(at 4.055618 10.627868 270)
			(size 0.4318 0.4318)
			(layers "F.Cu" "F.Mask" "F.Paste")
			(net "GND")
		)
		(pad "DA52" smd circle
			(at 5.68325 10.627868 270)
			(size 0.4318 0.4318)
			(layers "F.Cu" "F.Mask" "F.Paste")
			(net "PD_CPU1_PROCDIS_COD_GTL_N")
		)
		(pad "DA54" smd circle
			(at 7.311136 10.627868 270)
			(size 0.4318 0.4318)
			(layers "F.Cu" "F.Mask" "F.Paste")
			(net "GND")
		)
		(pad "DA56" smd circle
			(at 8.939022 10.627868 270)
			(size 0.4318 0.4318)
			(layers "F.Cu" "F.Mask" "F.Paste")
			(net "GND")
		)
		(pad "DA58" smd circle
			(at 10.566654 10.627868 270)
			(size 0.4318 0.4318)
			(layers "F.Cu" "F.Mask" "F.Paste")
			(net "GND")
		)
		(pad "DA60" smd circle
			(at 12.19454 10.627868 270)
			(size 0.4318 0.4318)
			(layers "F.Cu" "F.Mask" "F.Paste")
			(net "GND")
		)
		(pad "DA62" smd circle
			(at 13.822426 10.627868 270)
			(size 0.4318 0.4318)
			(layers "F.Cu" "F.Mask" "F.Paste")
			(net "GND")
		)
		(pad "DA64" smd circle
			(at 15.450058 10.627868 270)
			(size 0.4318 0.4318)
			(layers "F.Cu" "F.Mask" "F.Paste")
			(net "PVCCINFAON_CPU1")
		)
		(pad "DA66" smd circle
			(at 17.07769 10.627868 270)
			(size 0.4318 0.4318)
			(layers "F.Cu" "F.Mask" "F.Paste")
			(net "GND")
		)
		(pad "DA68" smd circle
			(at 18.705576 10.627868 270)
			(size 0.4318 0.4318)
			(layers "F.Cu" "F.Mask" "F.Paste")
			(net "GND")
		)
		(pad "DA70" smd circle
			(at 20.333462 10.627868 270)
			(size 0.4318 0.4318)
			(layers "F.Cu" "F.Mask" "F.Paste")
			(net "TP_CPU1_SPARE4")
		)
		(pad "DA72" smd circle
			(at 21.961094 10.627868 270)
			(size 0.4318 0.4318)
			(layers "F.Cu" "F.Mask" "F.Paste")
			(net "GND")
		)
		(pad "DA74" smd circle
			(at 23.58898 10.627868 270)
			(size 0.4318 0.4318)
			(layers "F.Cu" "F.Mask" "F.Paste")
			(net "GND")
		)
		(pad "DA76" smd circle
			(at 25.216612 10.627868 270)
			(size 0.4318 0.4318)
			(layers "F.Cu" "F.Mask" "F.Paste")
			(net "Net_721")
		)
		(pad "DA78" smd circle
			(at 26.844498 10.627868 270)
			(size 0.4318 0.4318)
			(layers "F.Cu" "F.Mask" "F.Paste")
			(net "GND")
		)
		(pad "DA80" smd circle
			(at 28.472384 10.627868 270)
			(size 0.4318 0.4318)
			(layers "F.Cu" "F.Mask" "F.Paste")
			(net "GND")
		)
		(pad "DA82" smd circle
			(at 30.100016 10.627868 270)
			(size 0.4318 0.4318)
			(layers "F.Cu" "F.Mask" "F.Paste")
			(net "GND")
		)
		(pad "DA84" smd circle
			(at 31.727902 10.627868 270)
			(size 0.4318 0.4318)
			(layers "F.Cu" "F.Mask" "F.Paste")
			(net "GND")
		)
		(pad "DA86" smd circle
			(at 33.355534 10.627868 270)
			(size 0.4318 0.4318)
			(layers "F.Cu" "F.Mask" "F.Paste")
			(net "P5E_CPU1_PE3_TX_DP<12>")
		)
		(pad "DA88" smd circle
			(at 34.98342 10.627868 270)
			(size 0.4318 0.4318)
			(layers "F.Cu" "F.Mask" "F.Paste")
			(net "GND")
		)
		(pad "DA90" smd circle
			(at 36.611306 10.627868 270)
			(size 0.4318 0.4318)
			(layers "F.Cu" "F.Mask" "F.Paste")
			(net "P5E_CPU1_PE3_RX_DN<13>")
		)
		(pad "DB2" smd circle
			(at -36.611306 10.987532 270)
			(size 0.4318 0.4318)
			(layers "F.Cu" "F.Mask" "F.Paste")
			(net "UPI_CPU0_CPU1_P0P1_DN<13>")
		)
		(pad "DB4" smd circle
			(at -34.98342 10.987532 270)
			(size 0.4318 0.4318)
			(layers "F.Cu" "F.Mask" "F.Paste")
			(net "GND")
		)
		(pad "DB6" smd circle
			(at -33.355534 10.987532 270)
			(size 0.4318 0.4318)
			(layers "F.Cu" "F.Mask" "F.Paste")
			(net "UPI_CPU1_CPU0_P1P0_DP<12>")
		)
		(pad "DB8" smd circle
			(at -31.727902 10.987532 270)
			(size 0.4318 0.4318)
			(layers "F.Cu" "F.Mask" "F.Paste")
			(net "GND")
		)
		(pad "DB10" smd circle
			(at -30.100016 10.987532 270)
			(size 0.4318 0.4318)
			(layers "F.Cu" "F.Mask" "F.Paste")
			(net "P5E_CPU1_PE2_RX_DP<2>")
		)
		(pad "DB12" smd circle
			(at -28.472384 10.987532 270)
			(size 0.4318 0.4318)
			(layers "F.Cu" "F.Mask" "F.Paste")
			(net "GND")
		)
		(pad "DB14" smd circle
			(at -26.844498 10.987532 270)
			(size 0.4318 0.4318)
			(layers "F.Cu" "F.Mask" "F.Paste")
			(net "P5E_CPU1_PE2_TX_DN<3>")
		)
		(pad "DB16" smd circle
			(at -25.216612 10.987532 270)
			(size 0.4318 0.4318)
			(layers "F.Cu" "F.Mask" "F.Paste")
			(net "GND")
		)
		(pad "DB18" smd circle
			(at -23.58898 10.987532 270)
			(size 0.4318 0.4318)
			(layers "F.Cu" "F.Mask" "F.Paste")
			(net "M_H_CPU1_SB_DQS_DN<3>")
		)
		(pad "DB20" smd circle
			(at -21.961094 10.987532 270)
			(size 0.4318 0.4318)
			(layers "F.Cu" "F.Mask" "F.Paste")
			(net "GND")
		)
		(pad "DB22" smd circle
			(at -20.333462 10.987532 270)
			(size 0.4318 0.4318)
			(layers "F.Cu" "F.Mask" "F.Paste")
			(net "GND")
		)
		(pad "DB24" smd circle
			(at -18.705576 10.987532 270)
			(size 0.4318 0.4318)
			(layers "F.Cu" "F.Mask" "F.Paste")
			(net "M_H_CPU1_SB_DQS_DP<1>")
		)
		(pad "DB26" smd circle
			(at -17.07769 10.987532 270)
			(size 0.4318 0.4318)
			(layers "F.Cu" "F.Mask" "F.Paste")
			(net "GND")
		)
		(pad "DB28" smd circle
			(at -15.450058 10.987532 270)
			(size 0.4318 0.4318)
			(layers "F.Cu" "F.Mask" "F.Paste")
			(net "GND")
		)
		(pad "DB30" smd circle
			(at -13.822426 10.987532 270)
			(size 0.4318 0.4318)
			(layers "F.Cu" "F.Mask" "F.Paste")
			(net "M_H_CPU1_SB_DQS_DP<0>")
		)
		(pad "DB32" smd circle
			(at -12.19454 10.987532 270)
			(size 0.4318 0.4318)
			(layers "F.Cu" "F.Mask" "F.Paste")
			(net "GND")
		)
		(pad "DB34" smd circle
			(at -10.566654 10.987532 270)
			(size 0.4318 0.4318)
			(layers "F.Cu" "F.Mask" "F.Paste")
			(net "GND")
		)
		(pad "DB36" smd circle
			(at -8.939022 10.987532 270)
			(size 0.4318 0.4318)
			(layers "F.Cu" "F.Mask" "F.Paste")
			(net "M_H_CPU1_SB_DQS_DP<9>")
		)
		(pad "DB38" smd circle
			(at -7.311136 10.987532 270)
			(size 0.4318 0.4318)
			(layers "F.Cu" "F.Mask" "F.Paste")
			(net "GND")
		)
		(pad "DB40" smd circle
			(at -5.68325 10.987532 270)
			(size 0.4318 0.4318)
			(layers "F.Cu" "F.Mask" "F.Paste")
			(net "GND")
		)
		(pad "DB42" smd circle
			(at -4.055618 10.987532 270)
			(size 0.4318 0.4318)
			(layers "F.Cu" "F.Mask" "F.Paste")
			(net "M_H_CPU1_CLK_DP<1>")
		)
		(pad "DB44" smd circle
			(at -2.427732 10.987532 270)
			(size 0.4318 0.4318)
			(layers "F.Cu" "F.Mask" "F.Paste")
			(net "GND")
		)
		(pad "DB47" smd circle
			(at 1.613916 11.097514 270)
			(size 0.4318 0.4318)
			(layers "F.Cu" "F.Mask" "F.Paste")
			(net "GND")
		)
		(pad "DB49" smd circle
			(at 3.241802 11.097514 270)
			(size 0.4318 0.4318)
			(layers "F.Cu" "F.Mask" "F.Paste")
			(net "M_H_CPU1_SA_CA<0>")
		)
		(pad "DB51" smd circle
			(at 4.869434 11.097514 270)
			(size 0.4318 0.4318)
			(layers "F.Cu" "F.Mask" "F.Paste")
			(net "GND")
		)
		(pad "DB53" smd circle
			(at 6.49732 11.097514 270)
			(size 0.4318 0.4318)
			(layers "F.Cu" "F.Mask" "F.Paste")
			(net "GND")
		)
		(pad "DB55" smd circle
			(at 8.124952 11.097514 270)
			(size 0.4318 0.4318)
			(layers "F.Cu" "F.Mask" "F.Paste")
			(net "M_H_CPU1_SA_DQS_DP<4>")
		)
		(pad "DB57" smd circle
			(at 9.752838 11.097514 270)
			(size 0.4318 0.4318)
			(layers "F.Cu" "F.Mask" "F.Paste")
			(net "GND")
		)
		(pad "DB59" smd circle
			(at 11.380724 11.097514 270)
			(size 0.4318 0.4318)
			(layers "F.Cu" "F.Mask" "F.Paste")
			(net "GND")
		)
		(pad "DB61" smd circle
			(at 13.008356 11.097514 270)
			(size 0.4318 0.4318)
			(layers "F.Cu" "F.Mask" "F.Paste")
			(net "M_H_CPU1_SA_DQS_DP<3>")
		)
		(pad "DB63" smd circle
			(at 14.635988 11.097514 270)
			(size 0.4318 0.4318)
			(layers "F.Cu" "F.Mask" "F.Paste")
			(net "GND")
		)
		(pad "DB65" smd circle
			(at 16.263874 11.097514 270)
			(size 0.4318 0.4318)
			(layers "F.Cu" "F.Mask" "F.Paste")
			(net "GND")
		)
		(pad "DB67" smd circle
			(at 17.89176 11.097514 270)
			(size 0.4318 0.4318)
			(layers "F.Cu" "F.Mask" "F.Paste")
			(net "M_H_CPU1_SA_DQS_DP<2>")
		)
		(pad "DB69" smd circle
			(at 19.519392 11.097514 270)
			(size 0.4318 0.4318)
			(layers "F.Cu" "F.Mask" "F.Paste")
			(net "GND")
		)
		(pad "DB71" smd circle
			(at 21.147278 11.097514 270)
			(size 0.4318 0.4318)
			(layers "F.Cu" "F.Mask" "F.Paste")
			(net "GND")
		)
		(pad "DB73" smd circle
			(at 22.77491 11.097514 270)
			(size 0.4318 0.4318)
			(layers "F.Cu" "F.Mask" "F.Paste")
			(net "M_H_CPU1_SA_DQS_DN<1>")
		)
		(pad "DB75" smd circle
			(at 24.402796 11.097514 270)
			(size 0.4318 0.4318)
			(layers "F.Cu" "F.Mask" "F.Paste")
			(net "GND")
		)
		(pad "DB77" smd circle
			(at 26.030682 11.097514 270)
			(size 0.4318 0.4318)
			(layers "F.Cu" "F.Mask" "F.Paste")
			(net "GND")
		)
		(pad "DB79" smd circle
			(at 27.658314 11.097514 270)
			(size 0.4318 0.4318)
			(layers "F.Cu" "F.Mask" "F.Paste")
			(net "GND")
		)
		(pad "DB81" smd circle
			(at 29.2862 11.097514 270)
			(size 0.4318 0.4318)
			(layers "F.Cu" "F.Mask" "F.Paste")
			(net "GND")
		)
		(pad "DB83" smd circle
			(at 30.914086 11.097514 270)
			(size 0.4318 0.4318)
			(layers "F.Cu" "F.Mask" "F.Paste")
			(net "GND")
		)
	)
)
